(kicad_pcb
	(version 20260206)
	(generator "pcbnew")
	(generator_version "10.0")
	(general
		(thickness 1.6)
		(legacy_teardrops no)
	)
	(paper "A4")
	(title_block
		(title "03242023_DA0F0TMBIJ0_F0T_Motherboard_J_brd_V01_OCP.brd")
		(comment 1 "Grand Teton / footprint 3431 of 6105 (J28), pads 225-291 of 291")
	)
	(layers
		(0 "F.Cu" signal "TOP")
		(4 "In1.Cu" signal "GND")
		(6 "In2.Cu" signal "IN1")
		(8 "In3.Cu" signal "GND1")
		(10 "In4.Cu" signal "IN2")
		(12 "In5.Cu" signal "GND2")
		(14 "In6.Cu" signal "IN3")
		(16 "In7.Cu" signal "GND3")
		(18 "In8.Cu" signal "VCC")
		(20 "In9.Cu" signal "VCC1")
		(22 "In10.Cu" signal "GND4")
		(24 "In11.Cu" signal "IN4")
		(26 "In12.Cu" signal "GND5")
		(28 "In13.Cu" signal "IN5")
		(30 "In14.Cu" signal "GND6")
		(32 "In15.Cu" signal "IN6")
		(34 "In16.Cu" signal "GND7")
		(2 "B.Cu" signal "BOTTOM")
		(9 "F.Adhes" user "F.Adhesive")
		(11 "B.Adhes" user "B.Adhesive")
		(13 "F.Paste" user "Package Geometry/Pastemask Top")
		(15 "B.Paste" user "Package Geometry/Pastemask Bottom")
		(5 "F.SilkS" user "Ref Des/Silkscreen Top")
		(7 "B.SilkS" user "Ref Des/Silkscreen Bottom")
		(1 "F.Mask" user "Board Geometry/Soldermask Top")
		(3 "B.Mask" user "Board Geometry/Soldermask Bottom")
		(17 "Dwgs.User" user "User.Drawings")
		(19 "Cmts.User" user "User.Comments")
		(21 "Eco1.User" user "User.Eco1")
		(23 "Eco2.User" user "User.Eco2")
		(25 "Edge.Cuts" user "Board Geometry/Outline")
		(27 "Margin" user)
		(31 "F.CrtYd" user "Package Geometry/Place Bound Top")
		(29 "B.CrtYd" user "Package Geometry/Place Bound Bottom")
		(35 "F.Fab" user "Ref Des/Assembly Top")
		(33 "B.Fab" user "Ref Des/Assembly Bottom")
	)
	(footprint ""
		(layer "F.Cu")
		(at 175.95088 -258.091686)
		(property "Reference" "J28"
			(at -0.26924 -81.680812 0)
			(unlocked yes)
			(layer "F.SilkS")
			(effects
				(font
					(size 0.7874 0.5842)
					(thickness 0.1524)
				)
				(justify left)
			)
		)
		(property "Value" ""
			(at 0 0 0)
			(layer "F.Fab")
			(effects
				(font
					(size 1.27 1.27)
				)
			)
		)
		(duplicate_pad_numbers_are_jumpers no)
		(pad "225" smd rect
			(at 2.050034 9.774936 270)
			(size 0.519938 1.4986)
			(layers "F.Cu" "F.Mask" "F.Paste")
			(net "M_F_CPU1_SB_CA<5>")
		)
		(pad "226" smd rect
			(at 2.050034 10.625074 270)
			(size 0.519938 1.4986)
			(layers "F.Cu" "F.Mask" "F.Paste")
			(net "GND")
		)
		(pad "227" smd rect
			(at 2.050034 11.474958 270)
			(size 0.519938 1.4986)
			(layers "F.Cu" "F.Mask" "F.Paste")
			(net "M_F_CPU1_SB_PAR")
		)
		(pad "228" smd rect
			(at 2.050034 12.325096 270)
			(size 0.519938 1.4986)
			(layers "F.Cu" "F.Mask" "F.Paste")
			(net "GND")
		)
		(pad "229" smd rect
			(at 2.050034 13.17498 270)
			(size 0.519938 1.4986)
			(layers "F.Cu" "F.Mask" "F.Paste")
			(net "M_F_CPU1_SB_CS_N<3>")
		)
		(pad "230" smd rect
			(at 2.050034 14.025118 270)
			(size 0.519938 1.4986)
			(layers "F.Cu" "F.Mask" "F.Paste")
			(net "GND")
		)
		(pad "231" smd rect
			(at 2.050034 14.875002 270)
			(size 0.519938 1.4986)
			(layers "F.Cu" "F.Mask" "F.Paste")
			(net "TP_CHF_CPU1_DIMM2_FRU_5")
		)
		(pad "232" smd rect
			(at 2.050034 15.724886 270)
			(size 0.519938 1.4986)
			(layers "F.Cu" "F.Mask" "F.Paste")
			(net "TP_CHF_CPU1_DIMM2_FRU_6")
		)
		(pad "233" smd rect
			(at 2.050034 16.575024 270)
			(size 0.519938 1.4986)
			(layers "F.Cu" "F.Mask" "F.Paste")
			(net "GND")
		)
		(pad "234" smd rect
			(at 2.050034 17.424908 270)
			(size 0.519938 1.4986)
			(layers "F.Cu" "F.Mask" "F.Paste")
			(net "M_F_CPU1_SB_CB<6>")
		)
		(pad "235" smd rect
			(at 2.050034 18.275046 270)
			(size 0.519938 1.4986)
			(layers "F.Cu" "F.Mask" "F.Paste")
			(net "GND")
		)
		(pad "236" smd rect
			(at 2.050034 19.12493 270)
			(size 0.519938 1.4986)
			(layers "F.Cu" "F.Mask" "F.Paste")
			(net "M_F_CPU1_SB_CB<7>")
		)
		(pad "237" smd rect
			(at 2.050034 19.975068 270)
			(size 0.519938 1.4986)
			(layers "F.Cu" "F.Mask" "F.Paste")
			(net "GND")
		)
		(pad "238" smd rect
			(at 2.050034 20.824952 270)
			(size 0.519938 1.4986)
			(layers "F.Cu" "F.Mask" "F.Paste")
			(net "M_F_CPU1_SB_DQS_DN<4>")
		)
		(pad "239" smd rect
			(at 2.050034 21.67509 270)
			(size 0.519938 1.4986)
			(layers "F.Cu" "F.Mask" "F.Paste")
			(net "M_F_CPU1_SB_DQS_DP<4>")
		)
		(pad "240" smd rect
			(at 2.050034 22.524974 270)
			(size 0.519938 1.4986)
			(layers "F.Cu" "F.Mask" "F.Paste")
			(net "GND")
		)
		(pad "241" smd rect
			(at 2.050034 23.375112 270)
			(size 0.519938 1.4986)
			(layers "F.Cu" "F.Mask" "F.Paste")
			(net "M_F_CPU1_SB_CB<2>")
		)
		(pad "242" smd rect
			(at 2.050034 24.224996 270)
			(size 0.519938 1.4986)
			(layers "F.Cu" "F.Mask" "F.Paste")
			(net "GND")
		)
		(pad "243" smd rect
			(at 2.050034 25.07488 270)
			(size 0.519938 1.4986)
			(layers "F.Cu" "F.Mask" "F.Paste")
			(net "M_F_CPU1_SB_CB<3>")
		)
		(pad "244" smd rect
			(at 2.050034 25.925018 270)
			(size 0.519938 1.4986)
			(layers "F.Cu" "F.Mask" "F.Paste")
			(net "GND")
		)
		(pad "245" smd rect
			(at 2.050034 26.774902 270)
			(size 0.519938 1.4986)
			(layers "F.Cu" "F.Mask" "F.Paste")
			(net "M_F_CPU1_SB_DQ<2>")
		)
		(pad "246" smd rect
			(at 2.050034 27.62504 270)
			(size 0.519938 1.4986)
			(layers "F.Cu" "F.Mask" "F.Paste")
			(net "GND")
		)
		(pad "247" smd rect
			(at 2.050034 28.474924 270)
			(size 0.519938 1.4986)
			(layers "F.Cu" "F.Mask" "F.Paste")
			(net "M_F_CPU1_SB_DQ<3>")
		)
		(pad "248" smd rect
			(at 2.050034 29.325062 270)
			(size 0.519938 1.4986)
			(layers "F.Cu" "F.Mask" "F.Paste")
			(net "GND")
		)
		(pad "249" smd rect
			(at 2.050034 30.174946 270)
			(size 0.519938 1.4986)
			(layers "F.Cu" "F.Mask" "F.Paste")
			(net "M_F_CPU1_SB_DQS_DN<5>")
		)
		(pad "250" smd rect
			(at 2.050034 31.025084 270)
			(size 0.519938 1.4986)
			(layers "F.Cu" "F.Mask" "F.Paste")
			(net "M_F_CPU1_SB_DQS_DP<5>")
		)
		(pad "251" smd rect
			(at 2.050034 31.874968 270)
			(size 0.519938 1.4986)
			(layers "F.Cu" "F.Mask" "F.Paste")
			(net "GND")
		)
		(pad "252" smd rect
			(at 2.050034 32.725106 270)
			(size 0.519938 1.4986)
			(layers "F.Cu" "F.Mask" "F.Paste")
			(net "M_F_CPU1_SB_DQ<6>")
		)
		(pad "253" smd rect
			(at 2.050034 33.57499 270)
			(size 0.519938 1.4986)
			(layers "F.Cu" "F.Mask" "F.Paste")
			(net "GND")
		)
		(pad "254" smd rect
			(at 2.050034 34.425128 270)
			(size 0.519938 1.4986)
			(layers "F.Cu" "F.Mask" "F.Paste")
			(net "M_F_CPU1_SB_DQ<7>")
		)
		(pad "255" smd rect
			(at 2.050034 35.275012 270)
			(size 0.519938 1.4986)
			(layers "F.Cu" "F.Mask" "F.Paste")
			(net "GND")
		)
		(pad "256" smd rect
			(at 2.050034 36.124896 270)
			(size 0.519938 1.4986)
			(layers "F.Cu" "F.Mask" "F.Paste")
			(net "M_F_CPU1_SB_DQ<10>")
		)
		(pad "257" smd rect
			(at 2.050034 36.975034 270)
			(size 0.519938 1.4986)
			(layers "F.Cu" "F.Mask" "F.Paste")
			(net "GND")
		)
		(pad "258" smd rect
			(at 2.050034 37.824918 270)
			(size 0.519938 1.4986)
			(layers "F.Cu" "F.Mask" "F.Paste")
			(net "M_F_CPU1_SB_DQ<11>")
		)
		(pad "259" smd rect
			(at 2.050034 38.675056 270)
			(size 0.519938 1.4986)
			(layers "F.Cu" "F.Mask" "F.Paste")
			(net "GND")
		)
		(pad "260" smd rect
			(at 2.050034 39.52494 270)
			(size 0.519938 1.4986)
			(layers "F.Cu" "F.Mask" "F.Paste")
			(net "M_F_CPU1_SB_DQS_DN<6>")
		)
		(pad "261" smd rect
			(at 2.050034 40.375078 270)
			(size 0.519938 1.4986)
			(layers "F.Cu" "F.Mask" "F.Paste")
			(net "M_F_CPU1_SB_DQS_DP<6>")
		)
		(pad "262" smd rect
			(at 2.050034 41.224962 270)
			(size 0.519938 1.4986)
			(layers "F.Cu" "F.Mask" "F.Paste")
			(net "GND")
		)
		(pad "263" smd rect
			(at 2.050034 42.0751 270)
			(size 0.519938 1.4986)
			(layers "F.Cu" "F.Mask" "F.Paste")
			(net "M_F_CPU1_SB_DQ<14>")
		)
		(pad "264" smd rect
			(at 2.050034 42.924984 270)
			(size 0.519938 1.4986)
			(layers "F.Cu" "F.Mask" "F.Paste")
			(net "GND")
		)
		(pad "265" smd rect
			(at 2.050034 43.775122 270)
			(size 0.519938 1.4986)
			(layers "F.Cu" "F.Mask" "F.Paste")
			(net "M_F_CPU1_SB_DQ<15>")
		)
		(pad "266" smd rect
			(at 2.050034 44.625006 270)
			(size 0.519938 1.4986)
			(layers "F.Cu" "F.Mask" "F.Paste")
			(net "GND")
		)
		(pad "267" smd rect
			(at 2.050034 45.47489 270)
			(size 0.519938 1.4986)
			(layers "F.Cu" "F.Mask" "F.Paste")
			(net "M_F_CPU1_SB_DQ<18>")
		)
		(pad "268" smd rect
			(at 2.050034 46.325028 270)
			(size 0.519938 1.4986)
			(layers "F.Cu" "F.Mask" "F.Paste")
			(net "GND")
		)
		(pad "269" smd rect
			(at 2.050034 47.174912 270)
			(size 0.519938 1.4986)
			(layers "F.Cu" "F.Mask" "F.Paste")
			(net "M_F_CPU1_SB_DQ<19>")
		)
		(pad "270" smd rect
			(at 2.050034 48.02505 270)
			(size 0.519938 1.4986)
			(layers "F.Cu" "F.Mask" "F.Paste")
			(net "GND")
		)
		(pad "271" smd rect
			(at 2.050034 48.874934 270)
			(size 0.519938 1.4986)
			(layers "F.Cu" "F.Mask" "F.Paste")
			(net "M_F_CPU1_SB_DQS_DN<7>")
		)
		(pad "272" smd rect
			(at 2.050034 49.725072 270)
			(size 0.519938 1.4986)
			(layers "F.Cu" "F.Mask" "F.Paste")
			(net "M_F_CPU1_SB_DQS_DP<7>")
		)
		(pad "273" smd rect
			(at 2.050034 50.574956 270)
			(size 0.519938 1.4986)
			(layers "F.Cu" "F.Mask" "F.Paste")
			(net "GND")
		)
		(pad "274" smd rect
			(at 2.050034 51.425094 270)
			(size 0.519938 1.4986)
			(layers "F.Cu" "F.Mask" "F.Paste")
			(net "M_F_CPU1_SB_DQ<22>")
		)
		(pad "275" smd rect
			(at 2.050034 52.274978 270)
			(size 0.519938 1.4986)
			(layers "F.Cu" "F.Mask" "F.Paste")
			(net "GND")
		)
		(pad "276" smd rect
			(at 2.050034 53.125116 270)
			(size 0.519938 1.4986)
			(layers "F.Cu" "F.Mask" "F.Paste")
			(net "M_F_CPU1_SB_DQ<23>")
		)
		(pad "277" smd rect
			(at 2.050034 53.975 270)
			(size 0.519938 1.4986)
			(layers "F.Cu" "F.Mask" "F.Paste")
			(net "GND")
		)
		(pad "278" smd rect
			(at 2.050034 54.824884 270)
			(size 0.519938 1.4986)
			(layers "F.Cu" "F.Mask" "F.Paste")
			(net "M_F_CPU1_SB_DQ<26>")
		)
		(pad "279" smd rect
			(at 2.050034 55.675022 270)
			(size 0.519938 1.4986)
			(layers "F.Cu" "F.Mask" "F.Paste")
			(net "GND")
		)
		(pad "280" smd rect
			(at 2.050034 56.524906 270)
			(size 0.519938 1.4986)
			(layers "F.Cu" "F.Mask" "F.Paste")
			(net "M_F_CPU1_SB_DQ<27>")
		)
		(pad "281" smd rect
			(at 2.050034 57.375044 270)
			(size 0.519938 1.4986)
			(layers "F.Cu" "F.Mask" "F.Paste")
			(net "GND")
		)
		(pad "282" smd rect
			(at 2.050034 58.224928 270)
			(size 0.519938 1.4986)
			(layers "F.Cu" "F.Mask" "F.Paste")
			(net "M_F_CPU1_SB_DQS_DN<8>")
		)
		(pad "283" smd rect
			(at 2.050034 59.075066 270)
			(size 0.519938 1.4986)
			(layers "F.Cu" "F.Mask" "F.Paste")
			(net "M_F_CPU1_SB_DQS_DP<8>")
		)
		(pad "284" smd rect
			(at 2.050034 59.92495 270)
			(size 0.519938 1.4986)
			(layers "F.Cu" "F.Mask" "F.Paste")
			(net "GND")
		)
		(pad "285" smd rect
			(at 2.050034 60.775088 270)
			(size 0.519938 1.4986)
			(layers "F.Cu" "F.Mask" "F.Paste")
			(net "M_F_CPU1_SB_DQ<30>")
		)
		(pad "286" smd rect
			(at 2.050034 61.624972 270)
			(size 0.519938 1.4986)
			(layers "F.Cu" "F.Mask" "F.Paste")
			(net "GND")
		)
		(pad "287" smd rect
			(at 2.050034 62.47511 270)
			(size 0.519938 1.4986)
			(layers "F.Cu" "F.Mask" "F.Paste")
			(net "M_F_CPU1_SB_DQ<31>")
		)
		(pad "288" smd rect
			(at 2.050034 63.324994 270)
			(size 0.519938 1.4986)
			(layers "F.Cu" "F.Mask" "F.Paste")
			(net "GND")
		)
		(pad "G1" thru_hole oval
			(at 0 -68.97497)
			(size 2.8194 1.5748)
			(drill oval 2.4384 1.1938)
			(layers "*.Cu" "*.Mask")
			(remove_unused_layers no)
			(net "GND")
			(clearance 0.127)
			(thermal_gap 0.127)
		)
		(pad "G2" thru_hole oval
			(at 0 3.875024)
			(size 2.8194 1.5748)
			(drill oval 2.4384 1.1938)
			(layers "*.Cu" "*.Mask")
			(remove_unused_layers no)
			(net "GND")
			(clearance 0.127)
			(thermal_gap 0.127)
		)
		(pad "G3" thru_hole oval
			(at 0 68.97497)
			(size 2.8194 1.5748)
			(drill oval 2.4384 1.1938)
			(layers "*.Cu" "*.Mask")
			(remove_unused_layers no)
			(net "GND")
			(clearance 0.127)
			(thermal_gap 0.127)
		)
	)
)
